# BASEBOARD_FAB2 (Tioga Pass) — schematic netlist excerpt (pin names and nets, part order shuffled) for the footprints in the layout excerpt that follows; sources: Cadence DE-HDL packaged netlist, KiCad conversion of Wiwynn_Tioga_Pass_MB.brd

C1R25  CAP_A  0.1UF 16V 10% X7R  pkg 0402V  page 140 : A = P3V3_STBY ; B = GND

CR1M2  DIODEAC_DUAL_ARRAY  ESD3V3U4ULC IC  pkg SM9  page 176
  AC0  = USB2_P01_ESD_DP
  AC1  = USB2_P01_ESD_DN
  GND(0)  = GND
  AC2  = TP_USB_ESD_AC2
  AC3  = TP_USB_ESD_AC3
  OUT3  = TP_USB_ESD_OUT3
  OUT2  = TP_USB_ESD_OUT2
  OUT1  = USB2_P01_ESD_DN
  OUT0  = USB2_P01_ESD_DP

(kicad_pcb
	(version 20260206)
	(generator "pcbnew")
	(generator_version "10.0")
	(general
		(thickness 1.6)
		(legacy_teardrops no)
	)
	(paper "A4")
	(title_block
		(title "Wiwynn_Tioga_Pass_MB.brd")
		(comment 1 "Tioga Pass / footprints 3043-3044 of 4770")
	)
	(layers
		(0 "F.Cu" signal "TOP")
		(4 "In1.Cu" signal "L2GND")
		(6 "In2.Cu" signal "L3")
		(8 "In3.Cu" signal "L4GND")
		(10 "In4.Cu" signal "L5")
		(12 "In5.Cu" signal "L6GND")
		(14 "In6.Cu" signal "L7VCC")
		(16 "In7.Cu" signal "L8VCC")
		(18 "In8.Cu" signal "L9GND")
		(20 "In9.Cu" signal "L10")
		(22 "In10.Cu" signal "L11GND")
		(24 "In11.Cu" signal "L12")
		(26 "In12.Cu" signal "L13GND")
		(2 "B.Cu" signal "BOTTOM")
		(9 "F.Adhes" user "F.Adhesive")
		(11 "B.Adhes" user "B.Adhesive")
		(13 "F.Paste" user "Package Geometry/Pastemask Top")
		(15 "B.Paste" user "Package Geometry/Pastemask Bottom")
		(5 "F.SilkS" user "Ref Des/Silkscreen Top")
		(7 "B.SilkS" user "Ref Des/Silkscreen Bottom")
		(1 "F.Mask" user "Board Geometry/Soldermask Top")
		(3 "B.Mask" user "Board Geometry/Soldermask Bottom")
		(17 "Dwgs.User" user "User.Drawings")
		(19 "Cmts.User" user "User.Comments")
		(21 "Eco1.User" user "User.Eco1")
		(23 "Eco2.User" user "User.Eco2")
		(25 "Edge.Cuts" user "Board Geometry/Outline")
		(27 "Margin" user)
		(31 "F.CrtYd" user "Package Geometry/Place Bound Top")
		(29 "B.CrtYd" user "Package Geometry/Place Bound Bottom")
		(35 "F.Fab" user "Ref Des/Assembly Top")
		(33 "B.Fab" user "Ref Des/Assembly Bottom")
	)
	(footprint ""
		(layer "B.Cu")
		(at 476.310198 -124.756926)
		(property "Reference" "CR1M2"
			(at 1.082802 -1.040384 0)
			(unlocked yes)
			(layer "B.SilkS")
			(effects
				(font
					(size 0.7874 0.5842)
					(thickness 0.1524)
				)
				(justify left mirror)
			)
		)
		(property "Value" ""
			(at 0 0 0)
			(layer "B.Fab")
			(effects
				(font
					(size 1.27 1.27)
				)
				(justify mirror)
			)
		)
		(duplicate_pad_numbers_are_jumpers no)
		(fp_circle
			(center 0.690626 -0.00254)
			(end 0.817626 -0.00254)
			(stroke
				(width 0.254)
				(type default)
			)
			(fill no)
			(layer "B.SilkS")
		)
		(fp_rect
			(start 0.225552 2.167382)
			(end -0.809498 -0.167386)
			(stroke
				(width 0)
				(type default)
			)
			(fill no)
			(layer "B.CrtYd")
		)
		(fp_line
			(start -0.809498 -0.167386)
			(end -0.809498 2.167382)
			(stroke
				(width 0.1)
				(type default)
			)
			(layer "B.Fab")
		)
		(fp_line
			(start -0.809498 2.167382)
			(end 0.225552 2.167382)
			(stroke
				(width 0.1)
				(type default)
			)
			(layer "B.Fab")
		)
		(fp_line
			(start 0.225552 -0.167386)
			(end -0.809498 -0.167386)
			(stroke
				(width 0.1)
				(type default)
			)
			(layer "B.Fab")
		)
		(fp_line
			(start 0.225552 2.167382)
			(end 0.225552 -0.167386)
			(stroke
				(width 0.1)
				(type default)
			)
			(layer "B.Fab")
		)
		(fp_circle
			(center 0.589026 -0.5334)
			(end 0.716026 -0.5334)
			(stroke
				(width 0.254)
				(type default)
			)
			(fill no)
			(layer "B.Fab")
		)
		(pad "1" smd rect
			(at 0 0 180)
			(size 0.3556 0.2032)
			(layers "B.Cu" "B.Mask" "B.Paste")
			(net "USB2_P01_ESD_DP")
		)
		(pad "2" smd rect
			(at 0 0.500126 180)
			(size 0.3556 0.2032)
			(layers "B.Cu" "B.Mask" "B.Paste")
			(net "USB2_P01_ESD_DN")
		)
		(pad "3" smd rect
			(at -0.2921 0.999998 180)
			(size 0.9398 0.4064)
			(layers "B.Cu" "B.Mask" "B.Paste")
			(net "GND")
		)
		(pad "4" smd rect
			(at 0 1.500124 180)
			(size 0.3556 0.2032)
			(layers "B.Cu" "B.Mask" "B.Paste")
			(net "TP_USB_ESD_AC2")
		)
		(pad "5" smd rect
			(at 0 1.999996 180)
			(size 0.3556 0.2032)
			(layers "B.Cu" "B.Mask" "B.Paste")
			(net "TP_USB_ESD_AC3")
		)
		(pad "6" smd rect
			(at -0.583946 1.999996 180)
			(size 0.3556 0.2032)
			(layers "B.Cu" "B.Mask" "B.Paste")
			(net "TP_USB_ESD_OUT3")
		)
		(pad "7" smd rect
			(at -0.583946 1.500124 180)
			(size 0.3556 0.2032)
			(layers "B.Cu" "B.Mask" "B.Paste")
			(net "TP_USB_ESD_OUT2")
		)
		(pad "8" smd rect
			(at -0.583946 0.500126 180)
			(size 0.3556 0.2032)
			(layers "B.Cu" "B.Mask" "B.Paste")
			(net "USB2_P01_ESD_DN")
		)
		(pad "9" smd rect
			(at -0.583946 0 180)
			(size 0.3556 0.2032)
			(layers "B.Cu" "B.Mask" "B.Paste")
			(net "USB2_P01_ESD_DP")
		)
	)
	(footprint ""
		(layer "B.Cu")
		(at 492.540798 -26.257758 90)
		(property "Reference" "C1R25"
			(at 0.8382 -0.67818 90)
			(unlocked yes)
			(layer "B.SilkS")
			(effects
				(font
					(size 0.4064 0.254)
					(thickness 0.1524)
				)
				(justify left mirror)
			)
		)
		(property "Value" ""
			(at 0 0 90)
			(layer "B.Fab")
			(effects
				(font
					(size 1.27 1.27)
				)
				(justify mirror)
			)
		)
		(duplicate_pad_numbers_are_jumpers no)
		(fp_poly
			(pts
				(xy -0.3048 -0.1016) (xy -0.3048 0.9906) (xy 0.3048 0.9906) (xy 0.3048 -0.1016)
			)
			(stroke
				(width 0)
				(type default)
			)
			(fill no)
			(layer "B.CrtYd")
		)
		(fp_line
			(start 0.3048 -0.1016)
			(end 0.3048 0.9906)
			(stroke
				(width 0.1)
				(type default)
			)
			(layer "B.Fab")
		)
		(fp_line
			(start -0.3048 -0.1016)
			(end 0.3048 -0.1016)
			(stroke
				(width 0.1)
				(type default)
			)
			(layer "B.Fab")
		)
		(fp_line
			(start 0.3048 0.9906)
			(end -0.3048 0.9906)
			(stroke
				(width 0.1)
				(type default)
			)
			(layer "B.Fab")
		)
		(fp_line
			(start -0.3048 0.9906)
			(end -0.3048 -0.1016)
			(stroke
				(width 0.1)
				(type default)
			)
			(layer "B.Fab")
		)
		(pad "1" smd rect
			(at 0 0 270)
			(size 0.508 0.508)
			(layers "B.Cu" "B.Mask" "B.Paste")
			(net "P3V3_STBY")
		)
		(pad "2" smd rect
			(at 0 0.889 270)
			(size 0.508 0.508)
			(layers "B.Cu" "B.Mask" "B.Paste")
			(net "GND")
		)
		(zone
			(layer "B.Cu")
			(hatch none 0.5)
			(connect_pads
				(clearance 0)
			)
			(min_thickness 0.25)
			(keepout
				(tracks allowed)
				(vias not_allowed)
				(pads allowed)
				(copperpour not_allowed)
				(footprints allowed)
			)
			(placement
				(enabled no)
				(sheetname "")
			)
			(fill
				(thermal_gap 0.5)
				(thermal_bridge_width 0.5)
				(island_removal_mode 0)
			)
			(polygon
				(pts
					(xy 492.794798 -26.511758) (xy 492.794798 -26.003758) (xy 493.175798 -26.003758) (xy 493.175798 -26.511758)
				)
			)
		)
		(zone
			(layer "B.Cu")
			(hatch none 0.5)
			(connect_pads
				(clearance 0)
			)
			(min_thickness 0.25)
			(keepout
				(tracks not_allowed)
				(vias allowed)
				(pads allowed)
				(copperpour not_allowed)
				(footprints allowed)
			)
			(placement
				(enabled no)
				(sheetname "")
			)
			(fill
				(thermal_gap 0.5)
				(thermal_bridge_width 0.5)
				(island_removal_mode 0)
			)
			(polygon
				(pts
					(xy 493.175798 -26.511758) (xy 493.175798 -26.003758) (xy 492.794798 -26.003758) (xy 492.794798 -26.511758)
				)
			)
		)
	)
)
